(kicad_pcb
	(version 20241229)
	(generator "pcbnew")
	(generator_version "9.0")
	(general
		(thickness 1.61)
		(legacy_teardrops no)
	)
	(paper "A3")
	(title_block
		(title "SO-DIMM DDR5 Tester")
		(date "2025-11-26")
		(rev "1.3.0")
		(comment 9 "footprints 282-287 of 627")
	)
	(layers
		(0 "F.Cu" signal)
		(4 "In1.Cu" power)
		(6 "In2.Cu" mixed)
		(8 "In3.Cu" power)
		(10 "In4.Cu" mixed)
		(12 "In5.Cu" power)
		(14 "In6.Cu" mixed)
		(16 "In7.Cu" power)
		(18 "In8.Cu" power)
		(20 "In9.Cu" mixed)
		(22 "In10.Cu" power)
		(2 "B.Cu" signal)
		(9 "F.Adhes" user "F.Adhesive")
		(11 "B.Adhes" user "B.Adhesive")
		(13 "F.Paste" user)
		(15 "B.Paste" user)
		(5 "F.SilkS" user "F.Silkscreen")
		(7 "B.SilkS" user "B.Silkscreen")
		(1 "F.Mask" user)
		(3 "B.Mask" user)
		(17 "Dwgs.User" user "User.Drawings")
		(19 "Cmts.User" user "User.Comments")
		(21 "Eco1.User" user "User.Eco1")
		(23 "Eco2.User" user "User.Eco2")
		(25 "Edge.Cuts" user)
		(27 "Margin" user)
		(31 "F.CrtYd" user "F.Courtyard")
		(29 "B.CrtYd" user "B.Courtyard")
		(35 "F.Fab" user)
		(33 "B.Fab" user)
	)
	(footprint "antmicro-footprints:LED_0603_1608Metric_G"
		(layer "F.Cu")
		(at 94.450501 116.426 -90)
		(descr "LED SMD 0603 Green")
		(tags "LED SMD 0603 Green")
		(property "Reference" "D8"
			(at -0.001 -0.901 270)
			(layer "F.SilkS")
			(hide yes)
			(effects
				(font
					(size 0.7 0.7)
					(thickness 0.15)
				)
				(justify left bottom)
			)
		)
		(property "Value" "LED_G_0603_KP-1608CGCK"
			(at -0.001 1.599 270)
			(layer "F.Fab")
			(effects
				(font
					(size 0.7 0.7)
					(thickness 0.15)
				)
				(justify left bottom)
			)
		)
		(property "Datasheet" "http://www.farnell.com/datasheets/2045956.pdf"
			(at 0 0 270)
			(layer "F.Fab")
			(hide yes)
			(effects
				(font
					(size 1.27 1.27)
					(thickness 0.15)
				)
			)
		)
		(property "Author" "Antmicro"
			(at -21.975499 210.876501 0)
			(layer "F.Fab")
			(hide yes)
			(effects
				(font
					(size 1 1)
					(thickness 0.15)
				)
			)
		)
		(property "License" "Apache-2.0"
			(at -21.975499 210.876501 0)
			(layer "F.Fab")
			(hide yes)
			(effects
				(font
					(size 1 1)
					(thickness 0.15)
				)
			)
		)
		(property "MPN" "KP-1608CGCK"
			(at -21.975499 210.876501 0)
			(layer "F.Fab")
			(hide yes)
			(effects
				(font
					(size 1 1)
					(thickness 0.15)
				)
			)
		)
		(property "Manufacturer" "Kingbright"
			(at -21.975499 210.876501 0)
			(layer "F.Fab")
			(hide yes)
			(effects
				(font
					(size 1 1)
					(thickness 0.15)
				)
			)
		)
		(sheetname "/FPGA bank 14/")
		(sheetfile "fpga-bank-14.kicad_sch")
		(attr smd)
		(fp_line
			(start -0.271 0.348)
			(end 0.269 0.348)
			(stroke
				(width 0.15)
				(type solid)
			)
			(layer "F.SilkS")
		)
		(fp_line
			(start 1.249 0.319)
			(end 1.249 -0.321)
			(stroke
				(width 0.15)
				(type solid)
			)
			(layer "F.SilkS")
		)
		(fp_line
			(start -0.107 -0.001)
			(end -0.291 -0.001)
			(stroke
				(width 0.1)
				(type solid)
			)
			(layer "F.SilkS")
		)
		(fp_line
			(start 0.092 -0.001)
			(end -0.107 0.198)
			(stroke
				(width 0.1)
				(type solid)
			)
			(layer "F.SilkS")
		)
		(fp_line
			(start 0.092 -0.001)
			(end 0.292 -0.001)
			(stroke
				(width 0.1)
				(type solid)
			)
			(layer "F.SilkS")
		)
		(fp_line
			(start -0.107 -0.201)
			(end -0.107 0.198)
			(stroke
				(width 0.1)
				(type solid)
			)
			(layer "F.SilkS")
		)
		(fp_line
			(start -0.107 -0.201)
			(end 0.092 -0.001)
			(stroke
				(width 0.1)
				(type solid)
			)
			(layer "F.SilkS")
		)
		(fp_line
			(start 0.092 -0.201)
			(end 0.092 0.198)
			(stroke
				(width 0.1)
				(type solid)
			)
			(layer "F.SilkS")
		)
		(fp_line
			(start -0.271 -0.349)
			(end 0.269 -0.349)
			(stroke
				(width 0.15)
				(type solid)
			)
			(layer "F.SilkS")
		)
		(fp_rect
			(start -1.2192 -0.6096)
			(end 1.27 0.6016)
			(stroke
				(width 0.05)
				(type solid)
			)
			(fill no)
			(layer "F.CrtYd")
		)
		(fp_line
			(start -0.202 0.201)
			(end 0.1 -0.001)
			(stroke
				(width 0.15)
				(type solid)
			)
			(layer "F.Fab")
		)
		(fp_line
			(start 0.198 0.201)
			(end 0.198 -0.101)
			(stroke
				(width 0.15)
				(type solid)
			)
			(layer "F.Fab")
		)
		(fp_line
			(start -0.849 0.025)
			(end -0.442 0.381)
			(stroke
				(width 0.15)
				(type solid)
			)
			(layer "F.Fab")
		)
		(fp_line
			(start -0.6 -0.001)
			(end -0.202 -0.001)
			(stroke
				(width 0.15)
				(type solid)
			)
			(layer "F.Fab")
		)
		(fp_line
			(start -0.202 -0.001)
			(end -0.202 0.201)
			(stroke
				(width 0.15)
				(type solid)
			)
			(layer "F.Fab")
		)
		(fp_line
			(start 0.1 -0.001)
			(end -0.202 -0.201)
			(stroke
				(width 0.15)
				(type solid)
			)
			(layer "F.Fab")
		)
		(fp_line
			(start 0.198 -0.001)
			(end 0.596 -0.001)
			(stroke
				(width 0.15)
				(type solid)
			)
			(layer "F.Fab")
		)
		(fp_line
			(start -0.202 -0.201)
			(end -0.202 -0.001)
			(stroke
				(width 0.15)
				(type solid)
			)
			(layer "F.Fab")
		)
		(fp_line
			(start 0.198 -0.201)
			(end 0.198 -0.101)
			(stroke
				(width 0.15)
				(type solid)
			)
			(layer "F.Fab")
		)
		(fp_rect
			(start -0.849 -0.401)
			(end 0.849 0.401)
			(stroke
				(width 0.15)
				(type solid)
			)
			(fill no)
			(layer "F.Fab")
		)
		(pad "1" smd rect
			(at -0.751 -0.001 90)
			(size 0.8 0.8)
			(layers "F.Cu" "F.Mask" "F.Paste")
			(net 200 "+3V3")
			(pinfunction "1")
			(pintype "passive")
		)
		(pad "2" smd rect
			(at 0.749 -0.001 90)
			(size 0.8 0.8)
			(layers "F.Cu" "F.Mask" "F.Paste")
			(net 33 "Net-(D8-Pad2)")
			(pinfunction "2")
			(pintype "passive")
		)
	)
	(footprint "antmicro-footprints:R_0402_1005Metric"
		(layer "F.Cu")
		(at 77.2 160.115 90)
		(descr "Resistor SMD 0402")
		(tags "resistor SMD 0402")
		(property "Reference" "R90"
			(at -1.122484 -0.772697 90)
			(layer "F.SilkS")
			(hide yes)
			(effects
				(font
					(size 0.7 0.7)
					(thickness 0.15)
				)
				(justify left bottom)
			)
		)
		(property "Value" "R_330R_0402"
			(at -1.011843 1.772047 90)
			(layer "F.Fab")
			(effects
				(font
					(size 0.7 0.7)
					(thickness 0.15)
				)
				(justify left bottom)
			)
		)
		(property "Datasheet" "https://www.bourns.com/docs/product-datasheets/cr.pdf"
			(at 0 0 90)
			(layer "F.Fab")
			(hide yes)
			(effects
				(font
					(size 1.27 1.27)
					(thickness 0.15)
				)
			)
		)
		(property "Author" "Antmicro"
			(at 237.315 82.915 0)
			(layer "F.Fab")
			(hide yes)
			(effects
				(font
					(size 1 1)
					(thickness 0.15)
				)
			)
		)
		(property "License" "Apache-2.0"
			(at 237.315 82.915 0)
			(layer "F.Fab")
			(hide yes)
			(effects
				(font
					(size 1 1)
					(thickness 0.15)
				)
			)
		)
		(property "MPN" "CR0402-FX-3300GLF"
			(at 237.315 82.915 0)
			(layer "F.Fab")
			(hide yes)
			(effects
				(font
					(size 1 1)
					(thickness 0.15)
				)
			)
		)
		(property "Manufacturer" "Bourns"
			(at 237.315 82.915 0)
			(layer "F.Fab")
			(hide yes)
			(effects
				(font
					(size 1 1)
					(thickness 0.15)
				)
			)
		)
		(property "Tolerance" "1%"
			(at 237.315 82.915 0)
			(layer "F.Fab")
			(hide yes)
			(effects
				(font
					(size 1 1)
					(thickness 0.15)
				)
			)
		)
		(property "Val" "330R"
			(at 237.315 82.915 0)
			(layer "F.Fab")
			(hide yes)
			(effects
				(font
					(size 1 1)
					(thickness 0.15)
				)
			)
		)
		(sheetname "/Debug FTDI/")
		(sheetfile "debug-ftdi.kicad_sch")
		(attr smd)
		(fp_rect
			(start -0.93 -0.47)
			(end 0.93 0.47)
			(stroke
				(width 0.05)
				(type solid)
			)
			(fill no)
			(layer "F.CrtYd")
		)
		(fp_rect
			(start -0.5 -0.25)
			(end 0.5 0.25)
			(stroke
				(width 0.15)
				(type solid)
			)
			(fill no)
			(layer "F.Fab")
		)
		(pad "1" smd roundrect
			(at -0.485 0 90)
			(size 0.59 0.64)
			(layers "F.Cu" "F.Mask" "F.Paste")
			(roundrect_rratio 0.25)
			(net 1 "GND")
			(pintype "passive")
		)
		(pad "2" smd roundrect
			(at 0.485 0 90)
			(size 0.59 0.64)
			(layers "F.Cu" "F.Mask" "F.Paste")
			(roundrect_rratio 0.25)
			(net 593 "Net-(C133-Pad1)")
			(pintype "passive")
		)
	)
	(footprint "antmicro-footprints:C_0402_1005Metric"
		(layer "F.Cu")
		(at 107.251 182.718 90)
		(descr "Capacitor SMD 0402")
		(tags "capacitor SMD 0402")
		(property "Reference" "C131"
			(at 0 -0.699 90)
			(layer "F.SilkS")
			(hide yes)
			(effects
				(font
					(size 0.7 0.7)
					(thickness 0.15)
				)
				(justify left bottom)
			)
		)
		(property "Value" "C_100n_0402"
			(at -1.022927 2.155213 90)
			(layer "F.Fab")
			(effects
				(font
					(size 0.7 0.7)
					(thickness 0.15)
				)
				(justify left bottom)
			)
		)
		(property "Datasheet" "https://www.murata.com/products/productdetail?partno=GRM155R61H104KE14%23"
			(at 0 0 90)
			(layer "F.Fab")
			(hide yes)
			(effects
				(font
					(size 1.27 1.27)
					(thickness 0.15)
				)
			)
		)
		(property "Author" "Antmicro"
			(at 289.969 75.467 0)
			(layer "F.Fab")
			(hide yes)
			(effects
				(font
					(size 1 1)
					(thickness 0.15)
				)
			)
		)
		(property "Dielectric" "X5R"
			(at 289.969 75.467 0)
			(layer "F.Fab")
			(hide yes)
			(effects
				(font
					(size 1 1)
					(thickness 0.15)
				)
			)
		)
		(property "License" "Apache-2.0"
			(at 289.969 75.467 0)
			(layer "F.Fab")
			(hide yes)
			(effects
				(font
					(size 1 1)
					(thickness 0.15)
				)
			)
		)
		(property "MPN" "GRM155R61H104KE14D"
			(at 289.969 75.467 0)
			(layer "F.Fab")
			(hide yes)
			(effects
				(font
					(size 1 1)
					(thickness 0.15)
				)
			)
		)
		(property "Manufacturer" "Murata"
			(at 289.969 75.467 0)
			(layer "F.Fab")
			(hide yes)
			(effects
				(font
					(size 1 1)
					(thickness 0.15)
				)
			)
		)
		(property "Val" "100n"
			(at 289.969 75.467 0)
			(layer "F.Fab")
			(hide yes)
			(effects
				(font
					(size 1 1)
					(thickness 0.15)
				)
			)
		)
		(property "Voltage" "50V"
			(at 289.969 75.467 0)
			(layer "F.Fab")
			(hide yes)
			(effects
				(font
					(size 1 1)
					(thickness 0.15)
				)
			)
		)
		(sheetname "/Debug FTDI/")
		(sheetfile "debug-ftdi.kicad_sch")
		(attr smd)
		(fp_rect
			(start -0.9659 -0.481258)
			(end 0.9649 0.458742)
			(stroke
				(width 0.05)
				(type solid)
			)
			(fill no)
			(layer "F.CrtYd")
		)
		(fp_line
			(start 0.499 -0.25)
			(end 0.499 0.248)
			(stroke
				(width 0.15)
				(type solid)
			)
			(layer "F.Fab")
		)
		(fp_line
			(start -0.499 -0.25)
			(end 0.499 -0.25)
			(stroke
				(width 0.15)
				(type solid)
			)
			(layer "F.Fab")
		)
		(fp_line
			(start 0.499 0.248)
			(end -0.499 0.248)
			(stroke
				(width 0.15)
				(type solid)
			)
			(layer "F.Fab")
		)
		(fp_line
			(start -0.499 0.248)
			(end -0.499 -0.25)
			(stroke
				(width 0.15)
				(type solid)
			)
			(layer "F.Fab")
		)
		(pad "1" smd roundrect
			(at -0.484 0 90)
			(size 0.59 0.64)
			(layers "F.Cu" "F.Mask" "F.Paste")
			(roundrect_rratio 0.25)
			(net 1 "GND")
			(pintype "passive")
		)
		(pad "2" smd roundrect
			(at 0.484 0 90)
			(size 0.59 0.64)
			(layers "F.Cu" "F.Mask" "F.Paste")
			(roundrect_rratio 0.25)
			(net 41 "+3V3_AON")
			(pintype "passive")
		)
	)
	(footprint "antmicro-footprints:TP_SMD_1mm"
		(layer "F.Cu")
		(at 186.5 159.2)
		(property "Reference" "TP13"
			(at 0 -0.731898 0)
			(layer "F.SilkS")
			(hide yes)
			(effects
				(font
					(size 0.7 0.7)
					(thickness 0.15)
				)
				(justify left bottom)
			)
		)
		(property "Value" "TP_1mm_SMD"
			(at 0 1.4 0)
			(layer "F.Fab")
			(effects
				(font
					(size 0.7 0.7)
					(thickness 0.15)
				)
				(justify left bottom)
			)
		)
		(property "Author" "Antmicro"
			(at 0 0 0)
			(layer "F.Fab")
			(hide yes)
			(effects
				(font
					(size 1 1)
					(thickness 0.15)
				)
			)
		)
		(property "License" "Apache-2.0"
			(at 0 0 0)
			(layer "F.Fab")
			(hide yes)
			(effects
				(font
					(size 1 1)
					(thickness 0.15)
				)
			)
		)
		(property "MPN" ""
			(at 0 0 0)
			(layer "F.Fab")
			(hide yes)
			(effects
				(font
					(size 1 1)
					(thickness 0.15)
				)
			)
		)
		(property "Manufacturer" ""
			(at 0 0 0)
			(layer "F.Fab")
			(hide yes)
			(effects
				(font
					(size 1 1)
					(thickness 0.15)
				)
			)
		)
		(sheetname "/Supply/")
		(sheetfile "supply.kicad_sch")
		(attr exclude_from_pos_files)
		(pad "1" smd circle
			(at 0 0)
			(size 1 1)
			(layers "F.Cu" "F.Mask")
			(net 206 "+1V1")
			(pinfunction "1")
			(pintype "passive")
		)
	)
	(footprint "antmicro-footprints:SC70-3"
		(layer "F.Cu")
		(at 102.100501 120.876 180)
		(property "Reference" "Q10"
			(at 0 -1.6 180)
			(layer "F.SilkS")
			(hide yes)
			(effects
				(font
					(size 0.7 0.7)
					(thickness 0.15)
				)
				(justify left bottom)
			)
		)
		(property "Value" "BSS138PW,115"
			(at 0 2.3 180)
			(layer "F.Fab")
			(effects
				(font
					(size 0.7 0.7)
					(thickness 0.15)
				)
				(justify left bottom)
			)
		)
		(property "Datasheet" "https://assets.nexperia.com/documents/data-sheet/BSS138PW.pdf"
			(at 0 0 180)
			(layer "F.Fab")
			(hide yes)
			(effects
				(font
					(size 1.27 1.27)
					(thickness 0.15)
				)
			)
		)
		(property "Description" "Power MOSFET, N Channel, 60 V, 320 mA, 0.9 ohm, SOT-323, Surface Mount"
			(at 0 0 180)
			(layer "F.Fab")
			(hide yes)
			(effects
				(font
					(size 1.27 1.27)
					(thickness 0.15)
				)
			)
		)
		(property "Author" "Antmicro"
			(at 204.201002 241.752 0)
			(layer "F.Fab")
			(hide yes)
			(effects
				(font
					(size 1 1)
					(thickness 0.15)
				)
			)
		)
		(property "License" "Apache-2.0"
			(at 204.201002 241.752 0)
			(layer "F.Fab")
			(hide yes)
			(effects
				(font
					(size 1 1)
					(thickness 0.15)
				)
			)
		)
		(property "MPN" "BSS138PW,115"
			(at 204.201002 241.752 0)
			(layer "F.Fab")
			(hide yes)
			(effects
				(font
					(size 1 1)
					(thickness 0.15)
				)
			)
		)
		(property "Manufacturer" "Nexperia"
			(at 204.201002 241.752 0)
			(layer "F.Fab")
			(hide yes)
			(effects
				(font
					(size 1 1)
					(thickness 0.15)
				)
			)
		)
		(sheetname "/DDR5 SODIMM/")
		(sheetfile "ddr5-sodimm.kicad_sch")
		(attr smd)
		(fp_line
			(start 0.627 0.6)
			(end 0.627 1.001)
			(stroke
				(width 0.15)
				(type solid)
			)
			(layer "F.SilkS")
		)
		(fp_line
			(start 0.627 -0.6)
			(end 0.627 -0.999)
			(stroke
				(width 0.15)
				(type solid)
			)
			(layer "F.SilkS")
		)
		(fp_line
			(start -0.3 1)
			(end 0.627 1.001)
			(stroke
				(width 0.15)
				(type solid)
			)
			(layer "F.SilkS")
		)
		(fp_line
			(start -0.3 -1)
			(end 0.627 -0.999)
			(stroke
				(width 0.15)
				(type solid)
			)
			(layer "F.SilkS")
		)
		(fp_line
			(start 1.4 0.4)
			(end 0.9 0.4)
			(stroke
				(width 0.05)
				(type solid)
			)
			(layer "F.CrtYd")
		)
		(fp_line
			(start 1.4 -0.4)
			(end 1.4 0.4)
			(stroke
				(width 0.05)
				(type solid)
			)
			(layer "F.CrtYd")
		)
		(fp_line
			(start 0.9 1.3)
			(end -0.9 1.3)
			(stroke
				(width 0.05)
				(type solid)
			)
			(layer "F.CrtYd")
		)
		(fp_line
			(start 0.9 0.4)
			(end 0.9 1.3)
			(stroke
				(width 0.05)
				(type solid)
			)
			(layer "F.CrtYd")
		)
		(fp_line
			(start 0.9 -0.4)
			(end 1.4 -0.4)
			(stroke
				(width 0.05)
				(type solid)
			)
			(layer "F.CrtYd")
		)
		(fp_line
			(start 0.9 -1.3)
			(end 0.9 -0.4)
			(stroke
				(width 0.05)
				(type solid)
			)
			(layer "F.CrtYd")
		)
		(fp_line
			(start -0.9 1.3)
			(end -0.9 1)
			(stroke
				(width 0.05)
				(type solid)
			)
			(layer "F.CrtYd")
		)
		(fp_line
			(start -0.9 1)
			(end -1.4 1)
			(stroke
				(width 0.05)
				(type solid)
			)
			(layer "F.CrtYd")
		)
		(fp_line
			(start -0.9 -1)
			(end -1.4 -1)
			(stroke
				(width 0.05)
				(type solid)
			)
			(layer "F.CrtYd")
		)
		(fp_line
			(start -0.9 -1.3)
			(end 0.9 -1.3)
			(stroke
				(width 0.05)
				(type solid)
			)
			(layer "F.CrtYd")
		)
		(fp_line
			(start -0.9 -1.3)
			(end -0.9 -1)
			(stroke
				(width 0.05)
				(type solid)
			)
			(layer "F.CrtYd")
		)
		(fp_line
			(start -1.4 1)
			(end -1.4 -1)
			(stroke
				(width 0.05)
				(type solid)
			)
			(layer "F.CrtYd")
		)
		(fp_rect
			(start -0.623 -0.999)
			(end 0.627 1.001)
			(stroke
				(width 0.15)
				(type solid)
			)
			(fill no)
			(layer "F.Fab")
		)
		(pad "1" smd rect
			(at -1.051 -0.65 270)
			(size 0.6 0.6)
			(layers "F.Cu" "F.Mask" "F.Paste")
			(net 235 "HOT_SWAP_GREEN")
			(pinfunction "G")
			(pintype "input")
		)
		(pad "2" smd rect
			(at -1.051 0.65 270)
			(size 0.6 0.6)
			(layers "F.Cu" "F.Mask" "F.Paste")
			(net 1 "GND")
			(pinfunction "S")
			(pintype "passive")
		)
		(pad "3" smd rect
			(at 1.05 0 270)
			(size 0.6 0.6)
			(layers "F.Cu" "F.Mask" "F.Paste")
			(net 359 "Net-(Q10-D)")
			(pinfunction "D")
			(pintype "passive")
		)
	)
	(footprint "antmicro-footprints:NetTie-2_SMD_Pad0.127mm"
		(layer "F.Cu")
		(at 199.825 191.326)
		(descr "Net tie, 2 pin, 0.127mm  SMD pads")
		(tags "net tie")
		(property "Reference" "NT4"
			(at -0.128 -1.345 0)
			(layer "F.SilkS")
			(hide yes)
			(effects
				(font
					(size 0.7 0.7)
					(thickness 0.15)
				)
				(justify left bottom)
			)
		)
		(property "Value" "Net-Tie_P0.127mm"
			(at 0 1.199 0)
			(layer "F.Fab")
			(effects
				(font
					(size 0.7 0.7)
					(thickness 0.15)
				)
				(justify left bottom)
			)
		)
		(property "Author" "Antmicro"
			(at 0 0 0)
			(layer "F.Fab")
			(hide yes)
			(effects
				(font
					(size 1 1)
					(thickness 0.15)
				)
			)
		)
		(property "License" "Apache-2.0"
			(at 0 0 0)
			(layer "F.Fab")
			(hide yes)
			(effects
				(font
					(size 1 1)
					(thickness 0.15)
				)
			)
		)
		(property "MPN" ""
			(at 0 0 0)
			(layer "F.Fab")
			(hide yes)
			(effects
				(font
					(size 1 1)
					(thickness 0.15)
				)
			)
		)
		(property "Manufacturer" ""
			(at 0 0 0)
			(layer "F.Fab")
			(hide yes)
			(effects
				(font
					(size 1 1)
					(thickness 0.15)
				)
			)
		)
		(property ki_fp_filters "Net*Tie*")
		(sheetname "/Supply/")
		(sheetfile "supply.kicad_sch")
		(attr smd exclude_from_pos_files exclude_from_bom)
		(net_tie_pad_groups "1, 2")
		(fp_poly
			(pts
				(xy -0.0635 -0.0635) (xy 0.0625 -0.0635) (xy 0.0625 0.0635) (xy -0.0635 0.0635)
			)
			(stroke
				(width 0)
				(type solid)
			)
			(fill yes)
			(layer "F.Cu")
		)
		(pad "1" smd roundrect
			(at -0.127 0 180)
			(size 0.127 0.127)
			(layers "F.Cu")
			(roundrect_rratio 0.5)
			(chamfer_ratio 0)
			(chamfer top_left bottom_left)
			(net 131 "/Supply/1V7_SEN_+")
			(pinfunction "1")
			(pintype "passive")
		)
		(pad "2" smd roundrect
			(at 0.126 0)
			(size 0.127 0.127)
			(layers "F.Cu")
			(roundrect_rratio 0.5)
			(chamfer_ratio 0)
			(chamfer top_left bottom_left)
			(net 58 "/Supply/1V7_local")
			(pinfunction "2")
			(pintype "passive")
		)
	)
)
